(kicad_pcb
	(version 20260206)
	(generator "pcbnew")
	(generator_version "10.0")
	(general
		(thickness 1.6)
		(legacy_teardrops no)
	)
	(paper "A4")
	(title_block
		(title "04192023_DAF0TMB3IC0_F0TG_MB_C_brd_V02_OCP.brd")
		(comment 1 "Grand Teton / footprints 4112-4117 of 8354")
	)
	(layers
		(0 "F.Cu" signal "TOP")
		(4 "In1.Cu" signal "GND")
		(6 "In2.Cu" signal "IN1")
		(8 "In3.Cu" signal "GND1")
		(10 "In4.Cu" signal "IN2")
		(12 "In5.Cu" signal "GND2")
		(14 "In6.Cu" signal "IN3")
		(16 "In7.Cu" signal "GND3")
		(18 "In8.Cu" signal "VCC")
		(20 "In9.Cu" signal "VCC1")
		(22 "In10.Cu" signal "GND4")
		(24 "In11.Cu" signal "IN4")
		(26 "In12.Cu" signal "GND5")
		(28 "In13.Cu" signal "IN5")
		(30 "In14.Cu" signal "GND6")
		(32 "In15.Cu" signal "IN6")
		(34 "In16.Cu" signal "GND7")
		(2 "B.Cu" signal "BOTTOM")
		(9 "F.Adhes" user "F.Adhesive")
		(11 "B.Adhes" user "B.Adhesive")
		(13 "F.Paste" user "Package Geometry/Pastemask Top")
		(15 "B.Paste" user "Package Geometry/Pastemask Bottom")
		(5 "F.SilkS" user "Ref Des/Silkscreen Top")
		(7 "B.SilkS" user "Ref Des/Silkscreen Bottom")
		(1 "F.Mask" user "Board Geometry/Soldermask Top")
		(3 "B.Mask" user "Board Geometry/Soldermask Bottom")
		(17 "Dwgs.User" user "User.Drawings")
		(19 "Cmts.User" user "User.Comments")
		(21 "Eco1.User" user "User.Eco1")
		(23 "Eco2.User" user "User.Eco2")
		(25 "Edge.Cuts" user "Board Geometry/Outline")
		(27 "Margin" user)
		(31 "F.CrtYd" user "Package Geometry/Place Bound Top")
		(29 "B.CrtYd" user "Package Geometry/Place Bound Bottom")
		(35 "F.Fab" user "Ref Des/Assembly Top")
		(33 "B.Fab" user "Ref Des/Assembly Bottom")
	)
	(footprint ""
		(layer "F.Cu")
		(at 359.716578 -169.497756 90)
		(property "Reference" "PC568_C0P0_5"
			(at 0 0 90)
			(layer "F.SilkS")
			(hide yes)
			(effects
				(font
					(size 1.27 1.27)
				)
			)
		)
		(property "Value" ""
			(at 0 0 90)
			(layer "F.Fab")
			(effects
				(font
					(size 1.27 1.27)
				)
			)
		)
		(duplicate_pad_numbers_are_jumpers no)
		(fp_line
			(start 0.7874 -0.4064)
			(end 0.7874 0.4064)
			(stroke
				(width 0.1524)
				(type default)
			)
			(layer "F.SilkS")
		)
		(fp_line
			(start -0.7874 -0.4064)
			(end 0.7874 -0.4064)
			(stroke
				(width 0.1524)
				(type default)
			)
			(layer "F.SilkS")
		)
		(fp_line
			(start 0.7874 0.4064)
			(end -0.7874 0.4064)
			(stroke
				(width 0.1524)
				(type default)
			)
			(layer "F.SilkS")
		)
		(fp_line
			(start -0.7874 0.4064)
			(end -0.7874 -0.4064)
			(stroke
				(width 0.1524)
				(type default)
			)
			(layer "F.SilkS")
		)
		(fp_line
			(start -0.12065 -0.305054)
			(end -0.12065 -0.2794)
			(stroke
				(width 0.1)
				(type default)
			)
			(layer "F.Fab")
		)
		(fp_line
			(start -0.67945 -0.305054)
			(end -0.12065 -0.305054)
			(stroke
				(width 0.1)
				(type default)
			)
			(layer "F.Fab")
		)
		(fp_line
			(start 0.67945 -0.3048)
			(end 0.67945 0.3048)
			(stroke
				(width 0.1)
				(type default)
			)
			(layer "F.Fab")
		)
		(fp_line
			(start 0.12065 -0.3048)
			(end 0.67945 -0.3048)
			(stroke
				(width 0.1)
				(type default)
			)
			(layer "F.Fab")
		)
		(fp_line
			(start 0.12065 -0.2794)
			(end 0.12065 -0.3048)
			(stroke
				(width 0.1)
				(type default)
			)
			(layer "F.Fab")
		)
		(fp_line
			(start -0.12065 -0.2794)
			(end 0.12065 -0.2794)
			(stroke
				(width 0.1)
				(type default)
			)
			(layer "F.Fab")
		)
		(fp_line
			(start 0.120396 0.2794)
			(end -0.12065 0.2794)
			(stroke
				(width 0.1)
				(type default)
			)
			(layer "F.Fab")
		)
		(fp_line
			(start -0.12065 0.2794)
			(end -0.12065 0.3048)
			(stroke
				(width 0.1)
				(type default)
			)
			(layer "F.Fab")
		)
		(fp_line
			(start 0.67945 0.3048)
			(end 0.120396 0.3048)
			(stroke
				(width 0.1)
				(type default)
			)
			(layer "F.Fab")
		)
		(fp_line
			(start 0.120396 0.3048)
			(end 0.120396 0.2794)
			(stroke
				(width 0.1)
				(type default)
			)
			(layer "F.Fab")
		)
		(fp_line
			(start -0.12065 0.3048)
			(end -0.67945 0.3048)
			(stroke
				(width 0.1)
				(type default)
			)
			(layer "F.Fab")
		)
		(fp_line
			(start -0.67945 0.3048)
			(end -0.67945 -0.305054)
			(stroke
				(width 0.1)
				(type default)
			)
			(layer "F.Fab")
		)
		(pad "1" smd circle
			(at -0.40005 0 90)
			(size 0 0)
			(layers "F.Cu" "F.Mask" "F.Paste")
			(net "PVDDCR_CPU0_P0_PVCC")
		)
		(pad "2" smd circle
			(at 0.40005 0 90)
			(size 0 0)
			(layers "F.Cu" "F.Mask" "F.Paste")
			(net "GND")
		)
	)
	(footprint ""
		(layer "F.Cu")
		(at 421.169592 -175.851312 180)
		(property "Reference" "PR297"
			(at 0 0 180)
			(layer "F.SilkS")
			(hide yes)
			(effects
				(font
					(size 1.27 1.27)
				)
			)
		)
		(property "Value" ""
			(at 0 0 180)
			(layer "F.Fab")
			(effects
				(font
					(size 1.27 1.27)
				)
			)
		)
		(duplicate_pad_numbers_are_jumpers no)
		(fp_line
			(start 0.7874 0.4064)
			(end -0.7874 0.4064)
			(stroke
				(width 0.1524)
				(type default)
			)
			(layer "F.SilkS")
		)
		(fp_line
			(start 0.7874 -0.4064)
			(end 0.7874 0.4064)
			(stroke
				(width 0.1524)
				(type default)
			)
			(layer "F.SilkS")
		)
		(fp_line
			(start -0.7874 0.4064)
			(end -0.7874 -0.4064)
			(stroke
				(width 0.1524)
				(type default)
			)
			(layer "F.SilkS")
		)
		(fp_line
			(start -0.7874 -0.4064)
			(end 0.7874 -0.4064)
			(stroke
				(width 0.1524)
				(type default)
			)
			(layer "F.SilkS")
		)
		(fp_line
			(start 0.67945 0.3048)
			(end 0.120396 0.3048)
			(stroke
				(width 0.1)
				(type default)
			)
			(layer "F.Fab")
		)
		(fp_line
			(start 0.67945 -0.3048)
			(end 0.67945 0.3048)
			(stroke
				(width 0.1)
				(type default)
			)
			(layer "F.Fab")
		)
		(fp_line
			(start 0.12065 -0.2794)
			(end 0.12065 -0.3048)
			(stroke
				(width 0.1)
				(type default)
			)
			(layer "F.Fab")
		)
		(fp_line
			(start 0.12065 -0.3048)
			(end 0.67945 -0.3048)
			(stroke
				(width 0.1)
				(type default)
			)
			(layer "F.Fab")
		)
		(fp_line
			(start 0.120396 0.3048)
			(end 0.120396 0.2794)
			(stroke
				(width 0.1)
				(type default)
			)
			(layer "F.Fab")
		)
		(fp_line
			(start 0.120396 0.2794)
			(end -0.12065 0.2794)
			(stroke
				(width 0.1)
				(type default)
			)
			(layer "F.Fab")
		)
		(fp_line
			(start -0.12065 0.3048)
			(end -0.67945 0.3048)
			(stroke
				(width 0.1)
				(type default)
			)
			(layer "F.Fab")
		)
		(fp_line
			(start -0.12065 0.2794)
			(end -0.12065 0.3048)
			(stroke
				(width 0.1)
				(type default)
			)
			(layer "F.Fab")
		)
		(fp_line
			(start -0.12065 -0.2794)
			(end 0.12065 -0.2794)
			(stroke
				(width 0.1)
				(type default)
			)
			(layer "F.Fab")
		)
		(fp_line
			(start -0.12065 -0.305054)
			(end -0.12065 -0.2794)
			(stroke
				(width 0.1)
				(type default)
			)
			(layer "F.Fab")
		)
		(fp_line
			(start -0.67945 0.3048)
			(end -0.67945 -0.305054)
			(stroke
				(width 0.1)
				(type default)
			)
			(layer "F.Fab")
		)
		(fp_line
			(start -0.67945 -0.305054)
			(end -0.12065 -0.305054)
			(stroke
				(width 0.1)
				(type default)
			)
			(layer "F.Fab")
		)
		(pad "1" smd circle
			(at -0.40005 0 180)
			(size 0 0)
			(layers "F.Cu" "F.Mask" "F.Paste")
			(net "VSENSE_VSS_SENSE_A_P0")
		)
		(pad "2" smd circle
			(at 0.40005 0 180)
			(size 0 0)
			(layers "F.Cu" "F.Mask" "F.Paste")
			(net "GND")
		)
	)
	(footprint ""
		(layer "F.Cu")
		(at 190.754 -54.991 90)
		(property "Reference" "Q8001"
			(at -1.869186 3.81254 90)
			(unlocked yes)
			(layer "F.SilkS")
			(effects
				(font
					(size 0.7874 0.5842)
					(thickness 0.1524)
				)
				(justify left)
			)
		)
		(property "Value" ""
			(at 0 0 90)
			(layer "F.Fab")
			(effects
				(font
					(size 1.27 1.27)
				)
			)
		)
		(duplicate_pad_numbers_are_jumpers no)
		(fp_line
			(start 1.332738 -1.100074)
			(end 1.332738 1.100074)
			(stroke
				(width 0.1524)
				(type default)
			)
			(layer "F.SilkS")
		)
		(fp_line
			(start 0.4826 -1.100074)
			(end 1.332738 -1.100074)
			(stroke
				(width 0.1524)
				(type default)
			)
			(layer "F.SilkS")
		)
		(fp_line
			(start -0.4826 -1.100074)
			(end 0 -0.541274)
			(stroke
				(width 0.1524)
				(type default)
			)
			(layer "F.SilkS")
		)
		(fp_line
			(start -1.332738 -1.100074)
			(end -0.4826 -1.100074)
			(stroke
				(width 0.1524)
				(type default)
			)
			(layer "F.SilkS")
		)
		(fp_line
			(start 0 -0.541274)
			(end 0.4826 -1.100074)
			(stroke
				(width 0.1524)
				(type default)
			)
			(layer "F.SilkS")
		)
		(fp_line
			(start 1.332738 1.100074)
			(end -1.332738 1.100074)
			(stroke
				(width 0.1524)
				(type default)
			)
			(layer "F.SilkS")
		)
		(fp_line
			(start -1.332738 1.100074)
			(end -1.332738 -1.100074)
			(stroke
				(width 0.1524)
				(type default)
			)
			(layer "F.SilkS")
		)
		(fp_poly
			(pts
				(xy -2.323338 0.090932) (xy -2.490978 -0.590804) (xy -1.725422 -0.417576)
			)
			(stroke
				(width 0)
				(type default)
			)
			(fill yes)
			(layer "F.SilkS")
		)
		(fp_line
			(start 0.674878 -1.100074)
			(end 0.674878 1.100074)
			(stroke
				(width 0.1)
				(type default)
			)
			(layer "F.Fab")
		)
		(fp_line
			(start -0.674878 -1.100074)
			(end 0.674878 -1.100074)
			(stroke
				(width 0.1)
				(type default)
			)
			(layer "F.Fab")
		)
		(fp_line
			(start 0.674878 1.100074)
			(end -0.674878 1.100074)
			(stroke
				(width 0.1)
				(type default)
			)
			(layer "F.Fab")
		)
		(fp_line
			(start -0.674878 1.100074)
			(end -0.674878 -1.100074)
			(stroke
				(width 0.1)
				(type default)
			)
			(layer "F.Fab")
		)
		(fp_poly
			(pts
				(xy -2.2352 -0.298958) (xy -2.2352 -1.001014) (xy -1.533144 -0.649986)
			)
			(stroke
				(width 0)
				(type default)
			)
			(fill yes)
			(layer "F.Fab")
		)
		(pad "1" smd rect
			(at -0.94996 -0.649986 180)
			(size 0.4318 0.508)
			(layers "F.Cu" "F.Mask" "F.Paste")
			(net "GND")
		)
		(pad "2" smd rect
			(at -0.94996 0 180)
			(size 0.4318 0.508)
			(layers "F.Cu" "F.Mask" "F.Paste")
			(net "P12V_SCM_FAULT_R_N")
		)
		(pad "3" smd rect
			(at -0.94996 0.649986 180)
			(size 0.4318 0.508)
			(layers "F.Cu" "F.Mask" "F.Paste")
			(net "LED_P12V_SCM_FAULT_D2")
		)
		(pad "4" smd rect
			(at 0.94996 0.649986 180)
			(size 0.4318 0.508)
			(layers "F.Cu" "F.Mask" "F.Paste")
			(net "GND")
		)
		(pad "5" smd rect
			(at 0.94996 0 180)
			(size 0.4318 0.508)
			(layers "F.Cu" "F.Mask" "F.Paste")
			(net "LED_P12V_SCM_FAULT_D1")
		)
		(pad "6" smd rect
			(at 0.94996 -0.649986 180)
			(size 0.4318 0.508)
			(layers "F.Cu" "F.Mask" "F.Paste")
			(net "LED_P12V_SCM_FAULT_D1")
		)
	)
	(footprint ""
		(layer "F.Cu")
		(at 358.796082 -259.845048)
		(property "Reference" "C2132"
			(at 0 0 0)
			(layer "F.SilkS")
			(hide yes)
			(effects
				(font
					(size 1.27 1.27)
				)
			)
		)
		(property "Value" ""
			(at 0 0 0)
			(layer "F.Fab")
			(effects
				(font
					(size 1.27 1.27)
				)
			)
		)
		(duplicate_pad_numbers_are_jumpers no)
		(fp_line
			(start -0.7874 -0.4064)
			(end 0.7874 -0.4064)
			(stroke
				(width 0.1524)
				(type default)
			)
			(layer "F.SilkS")
		)
		(fp_line
			(start -0.7874 0.4064)
			(end -0.7874 -0.4064)
			(stroke
				(width 0.1524)
				(type default)
			)
			(layer "F.SilkS")
		)
		(fp_line
			(start 0.7874 -0.4064)
			(end 0.7874 0.4064)
			(stroke
				(width 0.1524)
				(type default)
			)
			(layer "F.SilkS")
		)
		(fp_line
			(start 0.7874 0.4064)
			(end -0.7874 0.4064)
			(stroke
				(width 0.1524)
				(type default)
			)
			(layer "F.SilkS")
		)
		(fp_line
			(start -0.67945 -0.305054)
			(end -0.12065 -0.305054)
			(stroke
				(width 0.1)
				(type default)
			)
			(layer "F.Fab")
		)
		(fp_line
			(start -0.67945 0.3048)
			(end -0.67945 -0.305054)
			(stroke
				(width 0.1)
				(type default)
			)
			(layer "F.Fab")
		)
		(fp_line
			(start -0.12065 -0.305054)
			(end -0.12065 -0.2794)
			(stroke
				(width 0.1)
				(type default)
			)
			(layer "F.Fab")
		)
		(fp_line
			(start -0.12065 -0.2794)
			(end 0.12065 -0.2794)
			(stroke
				(width 0.1)
				(type default)
			)
			(layer "F.Fab")
		)
		(fp_line
			(start -0.12065 0.2794)
			(end -0.12065 0.3048)
			(stroke
				(width 0.1)
				(type default)
			)
			(layer "F.Fab")
		)
		(fp_line
			(start -0.12065 0.3048)
			(end -0.67945 0.3048)
			(stroke
				(width 0.1)
				(type default)
			)
			(layer "F.Fab")
		)
		(fp_line
			(start 0.120396 0.2794)
			(end -0.12065 0.2794)
			(stroke
				(width 0.1)
				(type default)
			)
			(layer "F.Fab")
		)
		(fp_line
			(start 0.120396 0.3048)
			(end 0.120396 0.2794)
			(stroke
				(width 0.1)
				(type default)
			)
			(layer "F.Fab")
		)
		(fp_line
			(start 0.12065 -0.3048)
			(end 0.67945 -0.3048)
			(stroke
				(width 0.1)
				(type default)
			)
			(layer "F.Fab")
		)
		(fp_line
			(start 0.12065 -0.2794)
			(end 0.12065 -0.3048)
			(stroke
				(width 0.1)
				(type default)
			)
			(layer "F.Fab")
		)
		(fp_line
			(start 0.67945 -0.3048)
			(end 0.67945 0.3048)
			(stroke
				(width 0.1)
				(type default)
			)
			(layer "F.Fab")
		)
		(fp_line
			(start 0.67945 0.3048)
			(end 0.120396 0.3048)
			(stroke
				(width 0.1)
				(type default)
			)
			(layer "F.Fab")
		)
		(pad "1" smd circle
			(at -0.40005 0)
			(size 0 0)
			(layers "F.Cu" "F.Mask" "F.Paste")
			(net "PVDD11_S3_P0")
		)
		(pad "2" smd circle
			(at 0.40005 0)
			(size 0 0)
			(layers "F.Cu" "F.Mask" "F.Paste")
			(net "GND")
		)
	)
	(footprint ""
		(layer "F.Cu")
		(at 257.85953 -52.685442)
		(property "Reference" "PC2281"
			(at 0 0 0)
			(layer "F.SilkS")
			(hide yes)
			(effects
				(font
					(size 1.27 1.27)
				)
			)
		)
		(property "Value" ""
			(at 0 0 0)
			(layer "F.Fab")
			(effects
				(font
					(size 1.27 1.27)
				)
			)
		)
		(duplicate_pad_numbers_are_jumpers no)
		(fp_line
			(start -0.7874 -0.4064)
			(end 0.7874 -0.4064)
			(stroke
				(width 0.1524)
				(type default)
			)
			(layer "F.SilkS")
		)
		(fp_line
			(start -0.7874 0.4064)
			(end -0.7874 -0.4064)
			(stroke
				(width 0.1524)
				(type default)
			)
			(layer "F.SilkS")
		)
		(fp_line
			(start 0.7874 -0.4064)
			(end 0.7874 0.4064)
			(stroke
				(width 0.1524)
				(type default)
			)
			(layer "F.SilkS")
		)
		(fp_line
			(start 0.7874 0.4064)
			(end -0.7874 0.4064)
			(stroke
				(width 0.1524)
				(type default)
			)
			(layer "F.SilkS")
		)
		(fp_line
			(start -0.67945 -0.305054)
			(end -0.12065 -0.305054)
			(stroke
				(width 0.1)
				(type default)
			)
			(layer "F.Fab")
		)
		(fp_line
			(start -0.67945 0.3048)
			(end -0.67945 -0.305054)
			(stroke
				(width 0.1)
				(type default)
			)
			(layer "F.Fab")
		)
		(fp_line
			(start -0.12065 -0.305054)
			(end -0.12065 -0.2794)
			(stroke
				(width 0.1)
				(type default)
			)
			(layer "F.Fab")
		)
		(fp_line
			(start -0.12065 -0.2794)
			(end 0.12065 -0.2794)
			(stroke
				(width 0.1)
				(type default)
			)
			(layer "F.Fab")
		)
		(fp_line
			(start -0.12065 0.2794)
			(end -0.12065 0.3048)
			(stroke
				(width 0.1)
				(type default)
			)
			(layer "F.Fab")
		)
		(fp_line
			(start -0.12065 0.3048)
			(end -0.67945 0.3048)
			(stroke
				(width 0.1)
				(type default)
			)
			(layer "F.Fab")
		)
		(fp_line
			(start 0.120396 0.2794)
			(end -0.12065 0.2794)
			(stroke
				(width 0.1)
				(type default)
			)
			(layer "F.Fab")
		)
		(fp_line
			(start 0.120396 0.3048)
			(end 0.120396 0.2794)
			(stroke
				(width 0.1)
				(type default)
			)
			(layer "F.Fab")
		)
		(fp_line
			(start 0.12065 -0.3048)
			(end 0.67945 -0.3048)
			(stroke
				(width 0.1)
				(type default)
			)
			(layer "F.Fab")
		)
		(fp_line
			(start 0.12065 -0.2794)
			(end 0.12065 -0.3048)
			(stroke
				(width 0.1)
				(type default)
			)
			(layer "F.Fab")
		)
		(fp_line
			(start 0.67945 -0.3048)
			(end 0.67945 0.3048)
			(stroke
				(width 0.1)
				(type default)
			)
			(layer "F.Fab")
		)
		(fp_line
			(start 0.67945 0.3048)
			(end 0.120396 0.3048)
			(stroke
				(width 0.1)
				(type default)
			)
			(layer "F.Fab")
		)
		(pad "1" smd circle
			(at -0.40005 0)
			(size 0 0)
			(layers "F.Cu" "F.Mask" "F.Paste")
			(net "P12V_E1S_SS_0")
		)
		(pad "2" smd circle
			(at 0.40005 0)
			(size 0 0)
			(layers "F.Cu" "F.Mask" "F.Paste")
			(net "GND")
		)
	)
	(footprint ""
		(layer "F.Cu")
		(at 351.486216 -440.211972)
		(property "Reference" "R4547"
			(at 0 0 0)
			(layer "F.SilkS")
			(hide yes)
			(effects
				(font
					(size 1.27 1.27)
				)
			)
		)
		(property "Value" ""
			(at 0 0 0)
			(layer "F.Fab")
			(effects
				(font
					(size 1.27 1.27)
				)
			)
		)
		(duplicate_pad_numbers_are_jumpers no)
		(fp_line
			(start -0.7874 -0.4064)
			(end 0.7874 -0.4064)
			(stroke
				(width 0.1524)
				(type default)
			)
			(layer "F.SilkS")
		)
		(fp_line
			(start -0.7874 0.4064)
			(end -0.7874 -0.4064)
			(stroke
				(width 0.1524)
				(type default)
			)
			(layer "F.SilkS")
		)
		(fp_line
			(start 0.7874 -0.4064)
			(end 0.7874 0.4064)
			(stroke
				(width 0.1524)
				(type default)
			)
			(layer "F.SilkS")
		)
		(fp_line
			(start 0.7874 0.4064)
			(end -0.7874 0.4064)
			(stroke
				(width 0.1524)
				(type default)
			)
			(layer "F.SilkS")
		)
		(fp_line
			(start -0.67945 -0.305054)
			(end -0.12065 -0.305054)
			(stroke
				(width 0.1)
				(type default)
			)
			(layer "F.Fab")
		)
		(fp_line
			(start -0.67945 0.3048)
			(end -0.67945 -0.305054)
			(stroke
				(width 0.1)
				(type default)
			)
			(layer "F.Fab")
		)
		(fp_line
			(start -0.12065 -0.305054)
			(end -0.12065 -0.2794)
			(stroke
				(width 0.1)
				(type default)
			)
			(layer "F.Fab")
		)
		(fp_line
			(start -0.12065 -0.2794)
			(end 0.12065 -0.2794)
			(stroke
				(width 0.1)
				(type default)
			)
			(layer "F.Fab")
		)
		(fp_line
			(start -0.12065 0.2794)
			(end -0.12065 0.3048)
			(stroke
				(width 0.1)
				(type default)
			)
			(layer "F.Fab")
		)
		(fp_line
			(start -0.12065 0.3048)
			(end -0.67945 0.3048)
			(stroke
				(width 0.1)
				(type default)
			)
			(layer "F.Fab")
		)
		(fp_line
			(start 0.120396 0.2794)
			(end -0.12065 0.2794)
			(stroke
				(width 0.1)
				(type default)
			)
			(layer "F.Fab")
		)
		(fp_line
			(start 0.120396 0.3048)
			(end 0.120396 0.2794)
			(stroke
				(width 0.1)
				(type default)
			)
			(layer "F.Fab")
		)
		(fp_line
			(start 0.12065 -0.3048)
			(end 0.67945 -0.3048)
			(stroke
				(width 0.1)
				(type default)
			)
			(layer "F.Fab")
		)
		(fp_line
			(start 0.12065 -0.2794)
			(end 0.12065 -0.3048)
			(stroke
				(width 0.1)
				(type default)
			)
			(layer "F.Fab")
		)
		(fp_line
			(start 0.67945 -0.3048)
			(end 0.67945 0.3048)
			(stroke
				(width 0.1)
				(type default)
			)
			(layer "F.Fab")
		)
		(fp_line
			(start 0.67945 0.3048)
			(end 0.120396 0.3048)
			(stroke
				(width 0.1)
				(type default)
			)
			(layer "F.Fab")
		)
		(pad "1" smd circle
			(at -0.40005 0)
			(size 0 0)
			(layers "F.Cu" "F.Mask" "F.Paste")
			(net "P3V3_AUX")
		)
		(pad "2" smd circle
			(at 0.40005 0)
			(size 0 0)
			(layers "F.Cu" "F.Mask" "F.Paste")
			(net "SWB_HSC_EN")
		)
	)
)
